FILE_TYPE = MACRO_DRAWING;
SET COLOR_WIRE YELLOW;
SET COLOR_PROP ORANGE;
SET COLOR_DOT WHITE;
SET COLOR_ARC YELLOW;
SET COLOR_BODY GREEN;
SET COLOR_NOTE PURPLE;
SET PROP_DISPLAY VALUE;
SET PAGE_NUMBER P124;
FORCEADD OFFPAGE..1
(-1925 2800);
FORCEPROP 2 LAST $XR1 219 
J 0
(-2297 2800);
DISPLAY 0.638298 (-2297 2800);
PAINT MONO (-2297 2800);
FORCEPROP 2 LAST $XR0 216 
J 0
(-2177 2800);
DISPLAY 0.638298 (-2177 2800);
PAINT MONO (-2177 2800);
FORCEPROP 2 LAST CDS_LIB standard
J 0
(-1925 2800);
PAINT MONO (-1925 2800);
DISPLAY INVISIBLE (-1925 2800);
FORCEPROP 1 LAST OFFPAGE TRUE
J 0
(-1600 2675);
DISPLAY 0.872340 (-1600 2675);
PAINT GREEN (-1600 2675);
DISPLAY INVISIBLE (-1600 2675);
FORCEPROP 1 LAST COMMENT_BODY TRUE
J 0
(-1800 2700);
DISPLAY 0.872340 (-1800 2700);
PAINT GREEN (-1800 2700);
DISPLAY INVISIBLE (-1800 2700);
FORCEPROP 2 LAST PATH I11
J 0
(-1875 2875);
DISPLAY 1.021277 (-1875 2875);
DISPLAY INVISIBLE (-1875 2875);
FORCEADD Q_RES..1
(-550 2800);
FORCEPROP 1 LAST PART_NUMBER CS00002JB13
J 0
(-650 2875);
DISPLAY 0.510638 (-650 2875);
DISPLAY INVISIBLE (-650 2875);
FORCEPROP 1 LAST PACK_TYPE 0402LF
J 0
(-300 2800);
DISPLAY 0.638298 (-300 2800);
FORCEPROP 1 LAST VALUE 0
J 2
(-400 2800);
DISPLAY 0.638298 (-400 2800);
FORCEPROP 1 LAST MATERIAL CHIP
J 0
(-650 2925);
DISPLAY 0.510638 (-650 2925);
FORCEPROP 1 LAST WATTAGE 1/16W
J 2
(-425 2925);
DISPLAY 0.510638 (-425 2925);
FORCEPROP 1 LAST TOLERANCE 5%
J 0
(-375 2800);
DISPLAY 0.638298 (-375 2800);
FORCEPROP 1 LAST $LOCATION R160
J 0
(-750 2800);
DISPLAY 0.638298 (-750 2800);
FORCEPROP 1 LASTPIN (-650 2800) $PN 1
J 0
(-638 2812);
DISPLAY 0.787234 (-638 2812);
FORCEPROP 1 LASTPIN (-450 2800) $PN 2
J 0
(-488 2812);
DISPLAY 0.787234 (-488 2812);
FORCEPROP 2 LAST CDS_LIB pure_quanta
J 0
(-550 2800);
PAINT MONO (-550 2800);
DISPLAY INVISIBLE (-550 2800);
FORCEPROP 1 LAST PATH I17
J 0
(-600 2950);
DISPLAY 0.978723 (-600 2950);
PAINT WHITE (-600 2950);
DISPLAY INVISIBLE (-600 2950);
FORCEPROP 2 LAST CDS_LOCATION R160
J 0
(-600 3000);
DISPLAY 1.021277 (-600 3000);
DISPLAY INVISIBLE (-600 3000);
FORCEPROP 2 LAST $SEC 1
J 0
(-600 3000);
DISPLAY 0.680851 (-600 3000);
PAINT MONO (-600 3000);
DISPLAY INVISIBLE (-600 3000);
FORCEPROP 2 LAST CDS_SEC 1
J 0
(-600 3000);
DISPLAY 1.021277 (-600 3000);
DISPLAY INVISIBLE (-600 3000);
FORCEADD Q_RES..1
(-550 1975);
FORCEPROP 1 LAST PART_NUMBER CS00002JB13
J 0
(-650 2050);
DISPLAY 0.510638 (-650 2050);
DISPLAY INVISIBLE (-650 2050);
FORCEPROP 1 LAST VALUE 0
J 2
(-400 1975);
DISPLAY 0.638298 (-400 1975);
FORCEPROP 1 LAST TOLERANCE 5%
J 0
(-375 1975);
DISPLAY 0.638298 (-375 1975);
FORCEPROP 1 LAST PACK_TYPE 0402LF
J 0
(-300 1975);
DISPLAY 0.638298 (-300 1975);
FORCEPROP 1 LAST WATTAGE 1/16W
J 2
(-425 2100);
DISPLAY 0.510638 (-425 2100);
FORCEPROP 1 LAST MATERIAL CHIP
J 0
(-650 2100);
DISPLAY 0.510638 (-650 2100);
FORCEPROP 1 LAST $LOCATION R162
J 0
(-750 1975);
DISPLAY 0.638298 (-750 1975);
FORCEPROP 1 LASTPIN (-650 1975) $PN 1
J 0
(-638 1987);
DISPLAY 0.787234 (-638 1987);
FORCEPROP 1 LASTPIN (-450 1975) $PN 2
J 0
(-488 1987);
DISPLAY 0.787234 (-488 1987);
FORCEPROP 2 LAST CDS_LIB pure_quanta
J 0
(-550 1975);
PAINT MONO (-550 1975);
DISPLAY INVISIBLE (-550 1975);
FORCEPROP 1 LAST PATH I19
J 0
(-600 2125);
DISPLAY 0.978723 (-600 2125);
PAINT WHITE (-600 2125);
DISPLAY INVISIBLE (-600 2125);
FORCEPROP 2 LAST CDS_LOCATION R162
J 0
(-600 2175);
DISPLAY 1.021277 (-600 2175);
DISPLAY INVISIBLE (-600 2175);
FORCEPROP 2 LAST $SEC 1
J 0
(-600 2175);
DISPLAY 0.680851 (-600 2175);
PAINT MONO (-600 2175);
DISPLAY INVISIBLE (-600 2175);
FORCEPROP 2 LAST CDS_SEC 1
J 0
(-600 2175);
DISPLAY 1.021277 (-600 2175);
DISPLAY INVISIBLE (-600 2175);
FORCEADD OFFPAGE..1
(-1925 1975);
FORCEPROP 2 LAST $XR1 219 
J 0
(-2297 1975);
DISPLAY 0.638298 (-2297 1975);
PAINT MONO (-2297 1975);
FORCEPROP 2 LAST $XR0 216 
J 0
(-2177 1975);
DISPLAY 0.638298 (-2177 1975);
PAINT MONO (-2177 1975);
FORCEPROP 2 LAST CDS_LIB standard
J 0
(-1925 1975);
PAINT MONO (-1925 1975);
DISPLAY INVISIBLE (-1925 1975);
FORCEPROP 1 LAST OFFPAGE TRUE
J 0
(-1600 1850);
DISPLAY 0.872340 (-1600 1850);
PAINT GREEN (-1600 1850);
DISPLAY INVISIBLE (-1600 1850);
FORCEPROP 1 LAST COMMENT_BODY TRUE
J 0
(-1800 1875);
DISPLAY 0.872340 (-1800 1875);
PAINT GREEN (-1800 1875);
DISPLAY INVISIBLE (-1800 1875);
FORCEPROP 2 LAST PATH I20
J 0
(-1875 2050);
DISPLAY 1.021277 (-1875 2050);
DISPLAY INVISIBLE (-1875 2050);
FORCEADD Q_RES..1
(-550 1125);
FORCEPROP 1 LAST PART_NUMBER CS00002JB13
J 0
(-650 1200);
DISPLAY 0.510638 (-650 1200);
DISPLAY INVISIBLE (-650 1200);
FORCEPROP 1 LAST WATTAGE 1/16W
J 2
(-425 1250);
DISPLAY 0.510638 (-425 1250);
FORCEPROP 1 LAST MATERIAL CHIP
J 0
(-650 1250);
DISPLAY 0.510638 (-650 1250);
FORCEPROP 1 LAST TOLERANCE 5%
J 0
(-375 1125);
DISPLAY 0.638298 (-375 1125);
FORCEPROP 1 LAST PACK_TYPE 0402LF
J 0
(-300 1125);
DISPLAY 0.638298 (-300 1125);
FORCEPROP 1 LAST VALUE 0
J 2
(-400 1125);
DISPLAY 0.638298 (-400 1125);
FORCEPROP 1 LAST $LOCATION R164
J 0
(-750 1125);
DISPLAY 0.638298 (-750 1125);
FORCEPROP 1 LASTPIN (-650 1125) $PN 1
J 0
(-638 1137);
DISPLAY 0.787234 (-638 1137);
FORCEPROP 1 LASTPIN (-450 1125) $PN 2
J 0
(-488 1137);
DISPLAY 0.787234 (-488 1137);
FORCEPROP 2 LAST CDS_LIB pure_quanta
J 0
(-550 1125);
PAINT MONO (-550 1125);
DISPLAY INVISIBLE (-550 1125);
FORCEPROP 1 LAST PATH I26
J 0
(-600 1275);
DISPLAY 0.978723 (-600 1275);
PAINT WHITE (-600 1275);
DISPLAY INVISIBLE (-600 1275);
FORCEPROP 2 LAST CDS_LOCATION R164
J 0
(-600 1325);
DISPLAY 1.021277 (-600 1325);
DISPLAY INVISIBLE (-600 1325);
FORCEPROP 2 LAST $SEC 1
J 0
(-600 1325);
DISPLAY 0.680851 (-600 1325);
PAINT MONO (-600 1325);
DISPLAY INVISIBLE (-600 1325);
FORCEPROP 2 LAST CDS_SEC 1
J 0
(-600 1325);
DISPLAY 1.021277 (-600 1325);
DISPLAY INVISIBLE (-600 1325);
FORCEADD OFFPAGE..1
(-1925 1125);
FORCEPROP 2 LAST $XR1 219 
J 0
(-2297 1125);
DISPLAY 0.638298 (-2297 1125);
PAINT MONO (-2297 1125);
FORCEPROP 2 LAST $XR0 216 
J 0
(-2177 1125);
DISPLAY 0.638298 (-2177 1125);
PAINT MONO (-2177 1125);
FORCEPROP 2 LAST CDS_LIB standard
J 0
(-1925 1125);
PAINT MONO (-1925 1125);
DISPLAY INVISIBLE (-1925 1125);
FORCEPROP 1 LAST OFFPAGE TRUE
J 0
(-1600 1000);
DISPLAY 0.872340 (-1600 1000);
PAINT GREEN (-1600 1000);
DISPLAY INVISIBLE (-1600 1000);
FORCEPROP 1 LAST COMMENT_BODY TRUE
J 0
(-1800 1025);
DISPLAY 0.872340 (-1800 1025);
PAINT GREEN (-1800 1025);
DISPLAY INVISIBLE (-1800 1025);
FORCEPROP 2 LAST PATH I27
J 0
(-1875 1200);
DISPLAY 1.021277 (-1875 1200);
DISPLAY INVISIBLE (-1875 1200);
FORCEADD Q_RES..1
(-550 300);
FORCEPROP 1 LAST PART_NUMBER CS00002JB13
J 0
(-600 350);
DISPLAY 0.404255 (-600 350);
DISPLAY INVISIBLE (-600 350);
FORCEPROP 1 LAST TOLERANCE 5%
J 0
(-375 300);
DISPLAY 0.510638 (-375 300);
FORCEPROP 1 LAST WATTAGE 1/16W
J 2
(-375 375);
DISPLAY 0.404255 (-375 375);
FORCEPROP 1 LAST VALUE 0
J 2
(-400 300);
DISPLAY 0.510638 (-400 300);
FORCEPROP 1 LAST MATERIAL CHIP
J 0
(-600 375);
DISPLAY 0.404255 (-600 375);
FORCEPROP 1 LAST PACK_TYPE 0402LF
J 0
(-300 300);
DISPLAY 0.510638 (-300 300);
FORCEPROP 1 LAST $LOCATION R166
J 0
(-750 300);
DISPLAY 0.638298 (-750 300);
FORCEPROP 1 LASTPIN (-650 300) $PN 1
J 0
(-638 312);
DISPLAY 0.787234 (-638 312);
FORCEPROP 1 LASTPIN (-450 300) $PN 2
J 0
(-488 312);
DISPLAY 0.787234 (-488 312);
FORCEPROP 2 LAST CDS_LIB pure_quanta
J 0
(-550 300);
PAINT MONO (-550 300);
DISPLAY INVISIBLE (-550 300);
FORCEPROP 1 LAST PATH I33
J 0
(-600 450);
DISPLAY 0.978723 (-600 450);
PAINT WHITE (-600 450);
DISPLAY INVISIBLE (-600 450);
FORCEPROP 2 LAST CDS_LOCATION R166
J 0
(-600 500);
DISPLAY 1.021277 (-600 500);
DISPLAY INVISIBLE (-600 500);
FORCEPROP 2 LAST $SEC 1
J 0
(-600 500);
DISPLAY 0.680851 (-600 500);
PAINT MONO (-600 500);
DISPLAY INVISIBLE (-600 500);
FORCEPROP 2 LAST CDS_SEC 1
J 0
(-600 500);
DISPLAY 1.021277 (-600 500);
DISPLAY INVISIBLE (-600 500);
FORCEADD OFFPAGE..1
(-1925 300);
FORCEPROP 2 LAST $XR1 219 
J 0
(-2297 300);
DISPLAY 0.638298 (-2297 300);
PAINT MONO (-2297 300);
FORCEPROP 2 LAST $XR0 216 
J 0
(-2177 300);
DISPLAY 0.638298 (-2177 300);
PAINT MONO (-2177 300);
FORCEPROP 2 LAST CDS_LIB standard
J 0
(-1925 300);
PAINT MONO (-1925 300);
DISPLAY INVISIBLE (-1925 300);
FORCEPROP 1 LAST OFFPAGE TRUE
J 0
(-1600 175);
DISPLAY 0.872340 (-1600 175);
PAINT GREEN (-1600 175);
DISPLAY INVISIBLE (-1600 175);
FORCEPROP 1 LAST COMMENT_BODY TRUE
J 0
(-1800 200);
DISPLAY 0.872340 (-1800 200);
PAINT GREEN (-1800 200);
DISPLAY INVISIBLE (-1800 200);
FORCEPROP 2 LAST PATH I34
J 0
(-1875 375);
DISPLAY 1.021277 (-1875 375);
DISPLAY INVISIBLE (-1875 375);
FORCEADD OFFPAGE..1
(-1925 -525);
FORCEPROP 2 LAST $XR1 219 
J 0
(-2297 -525);
DISPLAY 0.638298 (-2297 -525);
PAINT MONO (-2297 -525);
FORCEPROP 2 LAST $XR0 216 
J 0
(-2177 -525);
DISPLAY 0.638298 (-2177 -525);
PAINT MONO (-2177 -525);
FORCEPROP 2 LAST CDS_LIB standard
J 0
(-1925 -525);
PAINT MONO (-1925 -525);
DISPLAY INVISIBLE (-1925 -525);
FORCEPROP 1 LAST OFFPAGE TRUE
J 0
(-1600 -650);
DISPLAY 0.872340 (-1600 -650);
PAINT GREEN (-1600 -650);
DISPLAY INVISIBLE (-1600 -650);
FORCEPROP 1 LAST COMMENT_BODY TRUE
J 0
(-1800 -625);
DISPLAY 0.872340 (-1800 -625);
PAINT GREEN (-1800 -625);
DISPLAY INVISIBLE (-1800 -625);
FORCEPROP 2 LAST PATH I40
J 0
(-1875 -450);
DISPLAY 1.021277 (-1875 -450);
DISPLAY INVISIBLE (-1875 -450);
FORCEADD Q_RES..1
(-550 -525);
FORCEPROP 1 LAST PART_NUMBER CS00002JB13
J 0
(-600 -475);
DISPLAY 0.404255 (-600 -475);
DISPLAY INVISIBLE (-600 -475);
FORCEPROP 1 LAST WATTAGE 1/16W
J 2
(-375 -450);
DISPLAY 0.404255 (-375 -450);
FORCEPROP 1 LAST MATERIAL CHIP
J 0
(-600 -450);
DISPLAY 0.404255 (-600 -450);
FORCEPROP 1 LAST TOLERANCE 5%
J 0
(-375 -525);
DISPLAY 0.510638 (-375 -525);
FORCEPROP 1 LAST VALUE 0
J 2
(-400 -525);
DISPLAY 0.510638 (-400 -525);
FORCEPROP 1 LAST PACK_TYPE 0402LF
J 0
(-300 -525);
DISPLAY 0.510638 (-300 -525);
FORCEPROP 1 LAST $LOCATION R168
J 0
(-750 -525);
DISPLAY 0.638298 (-750 -525);
FORCEPROP 1 LASTPIN (-650 -525) $PN 1
J 0
(-638 -513);
DISPLAY 0.787234 (-638 -513);
FORCEPROP 1 LASTPIN (-450 -525) $PN 2
J 0
(-488 -513);
DISPLAY 0.787234 (-488 -513);
FORCEPROP 2 LAST CDS_LIB pure_quanta
J 0
(-550 -525);
PAINT MONO (-550 -525);
DISPLAY INVISIBLE (-550 -525);
FORCEPROP 1 LAST PATH I43
J 0
(-600 -375);
DISPLAY 0.978723 (-600 -375);
PAINT WHITE (-600 -375);
DISPLAY INVISIBLE (-600 -375);
FORCEPROP 2 LAST CDS_LOCATION R168
J 0
(-600 -325);
DISPLAY 1.021277 (-600 -325);
DISPLAY INVISIBLE (-600 -325);
FORCEPROP 2 LAST $SEC 1
J 0
(-600 -325);
DISPLAY 0.680851 (-600 -325);
PAINT MONO (-600 -325);
DISPLAY INVISIBLE (-600 -325);
FORCEPROP 2 LAST CDS_SEC 1
J 0
(-600 -325);
DISPLAY 1.021277 (-600 -325);
DISPLAY INVISIBLE (-600 -325);
FORCEADD UNIVERSAL_POWER..1
(4300 -250);
FORCEPROP 3 LASTPIN (4300 -300) SIG_NAME PVNN_TERM_CPU0\g
J 0
(4310 -290);
DISPLAY 0.659574 (4310 -290);
PAINT MONO (4310 -290);
DISPLAY INVISIBLE (4310 -290);
FORCEPROP 1 LAST HDL_POWER PVNN_TERM_CPU0
J 1
(4300 -200);
DISPLAY 0.872340 (4300 -200);
PAINT GREEN (4300 -200);
FORCEPROP 2 LAST CDS_LIB logical_power
J 0
(4300 -250);
PAINT MONO (4300 -250);
DISPLAY INVISIBLE (4300 -250);
FORCEPROP 1 LAST PATH I51
J 0
(4350 -225);
DISPLAY 0.872340 (4350 -225);
PAINT AQUA (4350 -225);
DISPLAY INVISIBLE (4350 -225);
FORCEADD Q_RES..1
(-550 -1375);
FORCEPROP 1 LAST PART_NUMBER CS00002JB13
J 0
(-600 -1325);
DISPLAY 0.404255 (-600 -1325);
DISPLAY INVISIBLE (-600 -1325);
FORCEPROP 1 LAST MATERIAL CHIP
J 0
(-600 -1300);
DISPLAY 0.404255 (-600 -1300);
FORCEPROP 1 LAST WATTAGE 1/16W
J 2
(-375 -1300);
DISPLAY 0.404255 (-375 -1300);
FORCEPROP 1 LAST PACK_TYPE 0402LF
J 0
(-300 -1375);
DISPLAY 0.510638 (-300 -1375);
FORCEPROP 1 LAST TOLERANCE 5%
J 0
(-375 -1375);
DISPLAY 0.510638 (-375 -1375);
FORCEPROP 1 LAST VALUE 0
J 2
(-400 -1375);
DISPLAY 0.510638 (-400 -1375);
FORCEPROP 1 LAST $LOCATION R171
J 0
(-750 -1375);
DISPLAY 0.638298 (-750 -1375);
FORCEPROP 1 LASTPIN (-650 -1375) $PN 1
J 0
(-638 -1363);
DISPLAY 0.787234 (-638 -1363);
FORCEPROP 1 LASTPIN (-450 -1375) $PN 2
J 0
(-488 -1363);
DISPLAY 0.787234 (-488 -1363);
FORCEPROP 2 LAST CDS_LIB pure_quanta
J 0
(-550 -1375);
PAINT MONO (-550 -1375);
DISPLAY INVISIBLE (-550 -1375);
FORCEPROP 1 LAST PATH I52
J 0
(-600 -1225);
DISPLAY 0.978723 (-600 -1225);
PAINT WHITE (-600 -1225);
DISPLAY INVISIBLE (-600 -1225);
FORCEPROP 2 LAST CDS_LOCATION R171
J 0
(-600 -1175);
DISPLAY 1.021277 (-600 -1175);
DISPLAY INVISIBLE (-600 -1175);
FORCEPROP 2 LAST $SEC 1
J 0
(-600 -1175);
DISPLAY 0.680851 (-600 -1175);
PAINT MONO (-600 -1175);
DISPLAY INVISIBLE (-600 -1175);
FORCEPROP 2 LAST CDS_SEC 1
J 0
(-600 -1175);
DISPLAY 1.021277 (-600 -1175);
DISPLAY INVISIBLE (-600 -1175);
FORCEADD OFFPAGE..1
(-1925 -1375);
FORCEPROP 2 LAST $XR1 219 
J 0
(-2297 -1375);
DISPLAY 0.638298 (-2297 -1375);
PAINT MONO (-2297 -1375);
FORCEPROP 2 LAST $XR0 216 
J 0
(-2177 -1375);
DISPLAY 0.638298 (-2177 -1375);
PAINT MONO (-2177 -1375);
FORCEPROP 2 LAST CDS_LIB standard
J 0
(-1925 -1375);
PAINT MONO (-1925 -1375);
DISPLAY INVISIBLE (-1925 -1375);
FORCEPROP 1 LAST OFFPAGE TRUE
J 0
(-1600 -1500);
DISPLAY 0.872340 (-1600 -1500);
PAINT GREEN (-1600 -1500);
DISPLAY INVISIBLE (-1600 -1500);
FORCEPROP 1 LAST COMMENT_BODY TRUE
J 0
(-1800 -1475);
DISPLAY 0.872340 (-1800 -1475);
PAINT GREEN (-1800 -1475);
DISPLAY INVISIBLE (-1800 -1475);
FORCEPROP 2 LAST PATH I54
J 0
(-1875 -1300);
DISPLAY 1.021277 (-1875 -1300);
DISPLAY INVISIBLE (-1875 -1300);
FORCEADD OFFPAGE..2
(4700 -525);
FORCEPROP 2 LAST $XR0 14 
J 0
(4889 -525);
DISPLAY 0.638298 (4889 -525);
PAINT MONO (4889 -525);
FORCEPROP 2 LAST CDS_LIB standard
J 0
(4700 -525);
DISPLAY INVISIBLE (4700 -525);
FORCEPROP 1 LAST OFFPAGE TRUE
J 0
(5025 -650);
DISPLAY 0.872340 (5025 -650);
PAINT GREEN (5025 -650);
DISPLAY INVISIBLE (5025 -650);
FORCEPROP 1 LAST COMMENT_BODY TRUE
J 0
(4655 -620);
DISPLAY 0.872340 (4655 -620);
PAINT GREEN (4655 -620);
DISPLAY INVISIBLE (4655 -620);
FORCEPROP 2 LAST PATH I57
J 0
(4900 -475);
DISPLAY 1.021277 (4900 -475);
DISPLAY INVISIBLE (4900 -475);
FORCEADD OFFPAGE..2
(4700 -1375);
FORCEPROP 2 LAST $XR0 14 
J 0
(4889 -1375);
DISPLAY 0.638298 (4889 -1375);
PAINT MONO (4889 -1375);
FORCEPROP 2 LAST CDS_LIB standard
J 0
(4700 -1375);
DISPLAY INVISIBLE (4700 -1375);
FORCEPROP 1 LAST OFFPAGE TRUE
J 0
(5025 -1500);
DISPLAY 0.872340 (5025 -1500);
PAINT GREEN (5025 -1500);
DISPLAY INVISIBLE (5025 -1500);
FORCEPROP 1 LAST COMMENT_BODY TRUE
J 0
(4655 -1470);
DISPLAY 0.872340 (4655 -1470);
PAINT GREEN (4655 -1470);
DISPLAY INVISIBLE (4655 -1470);
FORCEPROP 2 LAST PATH I58
J 0
(4900 -1325);
DISPLAY 1.021277 (4900 -1325);
DISPLAY INVISIBLE (4900 -1325);
FORCEADD UNIVERSAL_POWER..1
(4300 -1100);
FORCEPROP 3 LASTPIN (4300 -1150) SIG_NAME PVNN_TERM_CPU0\g
J 0
(4310 -1140);
DISPLAY 0.659574 (4310 -1140);
PAINT MONO (4310 -1140);
DISPLAY INVISIBLE (4310 -1140);
FORCEPROP 1 LAST HDL_POWER PVNN_TERM_CPU0
J 1
(4300 -1050);
DISPLAY 0.872340 (4300 -1050);
PAINT GREEN (4300 -1050);
FORCEPROP 2 LAST CDS_LIB logical_power
J 0
(4300 -1100);
PAINT MONO (4300 -1100);
DISPLAY INVISIBLE (4300 -1100);
FORCEPROP 1 LAST PATH I59
J 0
(4350 -1075);
DISPLAY 0.872340 (4350 -1075);
PAINT AQUA (4350 -1075);
DISPLAY INVISIBLE (4350 -1075);
FORCEADD Q_RES..1
(3700 -1200);
FORCEPROP 1 LAST PART_NUMBER CS11002FB07
J 0
(3575 -1150);
DISPLAY 0.404255 (3575 -1150);
DISPLAY INVISIBLE (3575 -1150);
FORCEPROP 1 LAST TOLERANCE 1%
J 0
(3900 -1200);
DISPLAY 0.510638 (3900 -1200);
FORCEPROP 1 LAST WATTAGE 1/16W
J 2
(3850 -1125);
DISPLAY 0.404255 (3850 -1125);
FORCEPROP 1 LAST VALUE 100
J 2
(3875 -1200);
DISPLAY 0.510638 (3875 -1200);
FORCEPROP 1 LAST MATERIAL CHIP
J 0
(3975 -1200);
DISPLAY 0.510638 (3975 -1200);
FORCEPROP 1 LAST PACK_TYPE 0402LF
J 0
(3575 -1125);
DISPLAY 0.404255 (3575 -1125);
FORCEPROP 1 LAST $LOCATION R185
J 0
(3500 -1200);
DISPLAY 0.638298 (3500 -1200);
FORCEPROP 1 LASTPIN (3600 -1200) $PN 1
J 0
(3612 -1188);
DISPLAY 0.787234 (3612 -1188);
FORCEPROP 1 LASTPIN (3800 -1200) $PN 2
J 0
(3762 -1188);
DISPLAY 0.787234 (3762 -1188);
FORCEPROP 2 LAST CDS_LIB pure_quanta
J 0
(3700 -1200);
PAINT MONO (3700 -1200);
DISPLAY INVISIBLE (3700 -1200);
FORCEPROP 1 LAST PATH I60
J 0
(3650 -1050);
DISPLAY 0.978723 (3650 -1050);
PAINT WHITE (3650 -1050);
DISPLAY INVISIBLE (3650 -1050);
FORCEPROP 2 LAST CDS_LOCATION R185
J 0
(3650 -1000);
DISPLAY 1.021277 (3650 -1000);
DISPLAY INVISIBLE (3650 -1000);
FORCEPROP 2 LAST $SEC 1
J 0
(3650 -1000);
DISPLAY 0.680851 (3650 -1000);
PAINT MONO (3650 -1000);
DISPLAY INVISIBLE (3650 -1000);
FORCEPROP 2 LAST CDS_SEC 1
J 0
(3650 -1000);
DISPLAY 1.021277 (3650 -1000);
DISPLAY INVISIBLE (3650 -1000);
FORCEADD Q_RES..1
(3700 -350);
FORCEPROP 1 LAST PART_NUMBER CS11002FB07
J 0
(3575 -300);
DISPLAY 0.404255 (3575 -300);
DISPLAY INVISIBLE (3575 -300);
FORCEPROP 1 LAST VALUE 100
J 2
(3875 -350);
DISPLAY 0.510638 (3875 -350);
FORCEPROP 1 LAST WATTAGE 1/16W
J 2
(3850 -275);
DISPLAY 0.404255 (3850 -275);
FORCEPROP 1 LAST PACK_TYPE 0402LF
J 0
(3575 -275);
DISPLAY 0.404255 (3575 -275);
FORCEPROP 1 LAST TOLERANCE 1%
J 0
(3900 -350);
DISPLAY 0.510638 (3900 -350);
FORCEPROP 1 LAST MATERIAL CHIP
J 0
(3975 -350);
DISPLAY 0.510638 (3975 -350);
FORCEPROP 1 LAST $LOCATION R183
J 0
(3500 -350);
DISPLAY 0.638298 (3500 -350);
FORCEPROP 1 LASTPIN (3600 -350) $PN 1
J 0
(3612 -338);
DISPLAY 0.787234 (3612 -338);
FORCEPROP 1 LASTPIN (3800 -350) $PN 2
J 0
(3762 -338);
DISPLAY 0.787234 (3762 -338);
FORCEPROP 2 LAST CDS_LIB pure_quanta
J 0
(3700 -350);
PAINT MONO (3700 -350);
DISPLAY INVISIBLE (3700 -350);
FORCEPROP 1 LAST PATH I62
J 0
(3650 -200);
DISPLAY 0.978723 (3650 -200);
PAINT WHITE (3650 -200);
DISPLAY INVISIBLE (3650 -200);
FORCEPROP 2 LAST CDS_LOCATION R183
J 0
(3650 -150);
DISPLAY 1.021277 (3650 -150);
DISPLAY INVISIBLE (3650 -150);
FORCEPROP 2 LAST $SEC 1
J 0
(3650 -150);
DISPLAY 0.680851 (3650 -150);
PAINT MONO (3650 -150);
DISPLAY INVISIBLE (3650 -150);
FORCEPROP 2 LAST CDS_SEC 1
J 0
(3650 -150);
DISPLAY 1.021277 (3650 -150);
DISPLAY INVISIBLE (3650 -150);
FORCEADD Q_RES..1
(3725 475);
FORCEPROP 1 LAST PART_NUMBER CS11002FB07
J 0
(3600 525);
DISPLAY 0.404255 (3600 525);
DISPLAY INVISIBLE (3600 525);
FORCEPROP 1 LAST PACK_TYPE 0402LF
J 0
(3600 550);
DISPLAY 0.404255 (3600 550);
FORCEPROP 1 LAST TOLERANCE 1%
J 0
(3925 475);
DISPLAY 0.510638 (3925 475);
FORCEPROP 1 LAST MATERIAL CHIP
J 0
(4000 475);
DISPLAY 0.510638 (4000 475);
FORCEPROP 1 LAST WATTAGE 1/16W
J 2
(3875 550);
DISPLAY 0.404255 (3875 550);
FORCEPROP 1 LAST VALUE 100
J 2
(3900 475);
DISPLAY 0.510638 (3900 475);
FORCEPROP 1 LAST $LOCATION R181
J 0
(3525 475);
DISPLAY 0.638298 (3525 475);
FORCEPROP 1 LASTPIN (3625 475) $PN 1
J 0
(3637 487);
DISPLAY 0.787234 (3637 487);
FORCEPROP 1 LASTPIN (3825 475) $PN 2
J 0
(3787 487);
DISPLAY 0.787234 (3787 487);
FORCEPROP 2 LAST CDS_LIB pure_quanta
J 0
(3725 475);
PAINT MONO (3725 475);
DISPLAY INVISIBLE (3725 475);
FORCEPROP 1 LAST PATH I68
J 0
(3675 625);
DISPLAY 0.978723 (3675 625);
PAINT WHITE (3675 625);
DISPLAY INVISIBLE (3675 625);
FORCEPROP 2 LAST CDS_LOCATION R181
J 0
(3675 675);
DISPLAY 1.021277 (3675 675);
DISPLAY INVISIBLE (3675 675);
FORCEPROP 2 LAST $SEC 1
J 0
(3675 675);
DISPLAY 0.680851 (3675 675);
PAINT MONO (3675 675);
DISPLAY INVISIBLE (3675 675);
FORCEPROP 2 LAST CDS_SEC 1
J 0
(3675 675);
DISPLAY 1.021277 (3675 675);
DISPLAY INVISIBLE (3675 675);
FORCEADD UNIVERSAL_POWER..1
(4325 575);
FORCEPROP 3 LASTPIN (4325 525) SIG_NAME PVCCD_HV_CPU0\g
J 0
(4335 535);
DISPLAY 0.659574 (4335 535);
PAINT MONO (4335 535);
DISPLAY INVISIBLE (4335 535);
FORCEPROP 1 LAST HDL_POWER PVCCD_HV_CPU0
J 1
(4325 625);
DISPLAY 0.872340 (4325 625);
PAINT GREEN (4325 625);
FORCEPROP 2 LAST CDS_LIB logical_power
J 0
(4325 575);
PAINT MONO (4325 575);
DISPLAY INVISIBLE (4325 575);
FORCEPROP 1 LAST PATH I69
J 0
(4375 600);
DISPLAY 0.872340 (4375 600);
PAINT AQUA (4375 600);
DISPLAY INVISIBLE (4375 600);
FORCEADD Q_RES..1
(3725 1300);
FORCEPROP 1 LAST PART_NUMBER CS11002FB07
J 0
(3600 1350);
DISPLAY 0.404255 (3600 1350);
DISPLAY INVISIBLE (3600 1350);
FORCEPROP 1 LAST WATTAGE 1/16W
J 2
(3875 1375);
DISPLAY 0.404255 (3875 1375);
FORCEPROP 1 LAST VALUE 100
J 2
(3900 1300);
DISPLAY 0.510638 (3900 1300);
FORCEPROP 1 LAST PACK_TYPE 0402LF
J 0
(3600 1375);
DISPLAY 0.404255 (3600 1375);
FORCEPROP 1 LAST TOLERANCE 1%
J 0
(3925 1300);
DISPLAY 0.510638 (3925 1300);
FORCEPROP 1 LAST MATERIAL CHIP
J 0
(4000 1300);
DISPLAY 0.510638 (4000 1300);
FORCEPROP 1 LAST $LOCATION R179
J 0
(3525 1300);
DISPLAY 0.638298 (3525 1300);
FORCEPROP 1 LASTPIN (3625 1300) $PN 1
J 0
(3637 1312);
DISPLAY 0.787234 (3637 1312);
FORCEPROP 1 LASTPIN (3825 1300) $PN 2
J 0
(3787 1312);
DISPLAY 0.787234 (3787 1312);
FORCEPROP 2 LAST CDS_LIB pure_quanta
J 0
(3725 1300);
PAINT MONO (3725 1300);
DISPLAY INVISIBLE (3725 1300);
FORCEPROP 1 LAST PATH I70
J 0
(3675 1450);
DISPLAY 0.978723 (3675 1450);
PAINT WHITE (3675 1450);
DISPLAY INVISIBLE (3675 1450);
FORCEPROP 2 LAST CDS_LOCATION R179
J 0
(3675 1500);
DISPLAY 1.021277 (3675 1500);
DISPLAY INVISIBLE (3675 1500);
FORCEPROP 2 LAST $SEC 1
J 0
(3675 1500);
DISPLAY 0.680851 (3675 1500);
PAINT MONO (3675 1500);
DISPLAY INVISIBLE (3675 1500);
FORCEPROP 2 LAST CDS_SEC 1
J 0
(3675 1500);
DISPLAY 1.021277 (3675 1500);
DISPLAY INVISIBLE (3675 1500);
FORCEADD UNIVERSAL_POWER..1
(4325 1400);
FORCEPROP 3 LASTPIN (4325 1350) SIG_NAME PVCCD_HV_CPU0\g
J 0
(4335 1360);
DISPLAY 0.659574 (4335 1360);
PAINT MONO (4335 1360);
DISPLAY INVISIBLE (4335 1360);
FORCEPROP 1 LAST HDL_POWER PVCCD_HV_CPU0
J 1
(4325 1450);
DISPLAY 0.872340 (4325 1450);
PAINT GREEN (4325 1450);
FORCEPROP 2 LAST CDS_LIB logical_power
J 0
(4325 1400);
PAINT MONO (4325 1400);
DISPLAY INVISIBLE (4325 1400);
FORCEPROP 1 LAST PATH I71
J 0
(4375 1425);
DISPLAY 0.872340 (4375 1425);
PAINT AQUA (4375 1425);
DISPLAY INVISIBLE (4375 1425);
FORCEADD Q_RES..1
(3725 2150);
FORCEPROP 1 LAST PART_NUMBER CS11002FB07
J 0
(3600 2200);
DISPLAY 0.404255 (3600 2200);
DISPLAY INVISIBLE (3600 2200);
FORCEPROP 1 LAST TOLERANCE 1%
J 0
(3925 2150);
DISPLAY 0.510638 (3925 2150);
FORCEPROP 1 LAST PACK_TYPE 0402LF
J 0
(3600 2225);
DISPLAY 0.404255 (3600 2225);
FORCEPROP 1 LAST WATTAGE 1/16W
J 2
(3875 2225);
DISPLAY 0.404255 (3875 2225);
FORCEPROP 1 LAST VALUE 100
J 2
(3900 2150);
DISPLAY 0.510638 (3900 2150);
FORCEPROP 1 LAST MATERIAL CHIP
J 0
(4000 2150);
DISPLAY 0.510638 (4000 2150);
FORCEPROP 1 LAST $LOCATION R177
J 0
(3525 2150);
DISPLAY 0.638298 (3525 2150);
FORCEPROP 1 LASTPIN (3625 2150) $PN 1
J 0
(3637 2162);
DISPLAY 0.787234 (3637 2162);
FORCEPROP 1 LASTPIN (3825 2150) $PN 2
J 0
(3787 2162);
DISPLAY 0.787234 (3787 2162);
FORCEPROP 2 LAST CDS_LIB pure_quanta
J 0
(3725 2150);
PAINT MONO (3725 2150);
DISPLAY INVISIBLE (3725 2150);
FORCEPROP 1 LAST PATH I72
J 0
(3675 2300);
DISPLAY 0.978723 (3675 2300);
PAINT WHITE (3675 2300);
DISPLAY INVISIBLE (3675 2300);
FORCEPROP 2 LAST CDS_LOCATION R177
J 0
(3675 2350);
DISPLAY 1.021277 (3675 2350);
DISPLAY INVISIBLE (3675 2350);
FORCEPROP 2 LAST $SEC 1
J 0
(3675 2350);
DISPLAY 0.680851 (3675 2350);
PAINT MONO (3675 2350);
DISPLAY INVISIBLE (3675 2350);
FORCEPROP 2 LAST CDS_SEC 1
J 0
(3675 2350);
DISPLAY 1.021277 (3675 2350);
DISPLAY INVISIBLE (3675 2350);
FORCEADD UNIVERSAL_POWER..1
(4325 2250);
FORCEPROP 3 LASTPIN (4325 2200) SIG_NAME PVCCD_HV_CPU0\g
J 0
(4335 2210);
DISPLAY 0.659574 (4335 2210);
PAINT MONO (4335 2210);
DISPLAY INVISIBLE (4335 2210);
FORCEPROP 1 LAST HDL_POWER PVCCD_HV_CPU0
J 1
(4325 2300);
DISPLAY 0.872340 (4325 2300);
PAINT GREEN (4325 2300);
FORCEPROP 2 LAST CDS_LIB logical_power
J 0
(4325 2250);
PAINT MONO (4325 2250);
DISPLAY INVISIBLE (4325 2250);
FORCEPROP 1 LAST PATH I73
J 0
(4375 2275);
DISPLAY 0.872340 (4375 2275);
PAINT AQUA (4375 2275);
DISPLAY INVISIBLE (4375 2275);
FORCEADD UNIVERSAL_POWER..1
(4325 3075);
FORCEPROP 3 LASTPIN (4325 3025) SIG_NAME PVCCD_HV_CPU0\g
J 0
(4335 3035);
DISPLAY 0.659574 (4335 3035);
PAINT MONO (4335 3035);
DISPLAY INVISIBLE (4335 3035);
FORCEPROP 1 LAST HDL_POWER PVCCD_HV_CPU0
J 1
(4325 3125);
DISPLAY 0.872340 (4325 3125);
PAINT GREEN (4325 3125);
FORCEPROP 2 LAST CDS_LIB logical_power
J 0
(4325 3075);
PAINT MONO (4325 3075);
DISPLAY INVISIBLE (4325 3075);
FORCEPROP 1 LAST PATH I75
J 0
(4375 3100);
DISPLAY 0.872340 (4375 3100);
PAINT AQUA (4375 3100);
DISPLAY INVISIBLE (4375 3100);
FORCEADD Q_RES..1
(3725 2975);
FORCEPROP 1 LAST PART_NUMBER CS11002FB07
J 0
(3600 3025);
DISPLAY 0.404255 (3600 3025);
DISPLAY INVISIBLE (3600 3025);
FORCEPROP 1 LAST TOLERANCE 1%
J 0
(3925 2975);
DISPLAY 0.510638 (3925 2975);
FORCEPROP 1 LAST MATERIAL CHIP
J 0
(4000 2975);
DISPLAY 0.510638 (4000 2975);
FORCEPROP 1 LAST WATTAGE 1/16W
J 2
(3875 3050);
DISPLAY 0.404255 (3875 3050);
FORCEPROP 1 LAST VALUE 100
J 2
(3900 2975);
DISPLAY 0.510638 (3900 2975);
FORCEPROP 1 LAST PACK_TYPE 0402LF
J 0
(3650 3050);
DISPLAY 0.404255 (3650 3050);
FORCEPROP 1 LAST LOCATION R175
J 0
(3525 2975);
DISPLAY 0.638298 (3525 2975);
FORCEPROP 1 LASTPIN (3625 2975) $PN 1
J 0
(3637 2987);
DISPLAY 0.787234 (3637 2987);
PAINT MONO (3637 2987);
FORCEPROP 1 LASTPIN (3825 2975) $PN 2
J 0
(3787 2987);
DISPLAY 0.787234 (3787 2987);
PAINT MONO (3787 2987);
FORCEPROP 2 LAST CDS_LIB pure_quanta
J 0
(3725 2975);
DISPLAY INVISIBLE (3725 2975);
FORCEPROP 1 LAST PATH I76
J 0
(3675 3125);
DISPLAY 0.978723 (3675 3125);
PAINT WHITE (3675 3125);
DISPLAY INVISIBLE (3675 3125);
FORCEPROP 0 LAST $SEC 1
J 0
(3875 3075);
DISPLAY 0.680851 (3875 3075);
PAINT MONO (3875 3075);
DISPLAY INVISIBLE (3875 3075);
FORCEPROP 0 LAST CDS_SEC 1
J 0
(3875 3075);
DISPLAY 1.021277 (3875 3075);
DISPLAY INVISIBLE (3875 3075);
FORCEADD Q_RES..1
(3700 -525);
FORCEPROP 1 LAST PART_NUMBER CS11002FB07
J 0
(3575 -475);
DISPLAY 0.404255 (3575 -475);
DISPLAY INVISIBLE (3575 -475);
FORCEPROP 1 LAST MATERIAL CHIP
J 0
(3975 -525);
DISPLAY 0.510638 (3975 -525);
FORCEPROP 1 LAST VALUE 100
J 2
(3875 -525);
DISPLAY 0.510638 (3875 -525);
FORCEPROP 1 LAST TOLERANCE 1%
J 0
(3900 -525);
DISPLAY 0.510638 (3900 -525);
FORCEPROP 1 LAST PACK_TYPE 0402LF
J 0
(3575 -450);
DISPLAY 0.404255 (3575 -450);
FORCEPROP 1 LAST WATTAGE 1/16W
J 2
(3850 -450);
DISPLAY 0.404255 (3850 -450);
FORCEPROP 1 LAST LOCATION R184
J 0
(3500 -525);
DISPLAY 0.638298 (3500 -525);
FORCEPROP 1 LASTPIN (3600 -525) $PN 1
J 0
(3612 -513);
DISPLAY 0.787234 (3612 -513);
PAINT MONO (3612 -513);
FORCEPROP 1 LASTPIN (3800 -525) $PN 2
J 0
(3762 -513);
DISPLAY 0.787234 (3762 -513);
PAINT MONO (3762 -513);
FORCEPROP 2 LAST CDS_LIB pure_quanta
J 0
(3700 -525);
DISPLAY INVISIBLE (3700 -525);
FORCEPROP 1 LAST PATH I77
J 0
(3650 -375);
DISPLAY 0.978723 (3650 -375);
PAINT WHITE (3650 -375);
DISPLAY INVISIBLE (3650 -375);
FORCEPROP 0 LAST $SEC 1
J 0
(3850 -425);
DISPLAY 0.680851 (3850 -425);
PAINT MONO (3850 -425);
DISPLAY INVISIBLE (3850 -425);
FORCEPROP 0 LAST CDS_SEC 1
J 0
(3850 -425);
DISPLAY 1.021277 (3850 -425);
DISPLAY INVISIBLE (3850 -425);
FORCEADD Q_RES..1
(3700 -1375);
FORCEPROP 1 LAST PART_NUMBER CS11002FB07
J 0
(3575 -1325);
DISPLAY 0.404255 (3575 -1325);
DISPLAY INVISIBLE (3575 -1325);
FORCEPROP 1 LAST VALUE 100
J 2
(3875 -1375);
DISPLAY 0.510638 (3875 -1375);
FORCEPROP 1 LAST TOLERANCE 1%
J 0
(3900 -1375);
DISPLAY 0.510638 (3900 -1375);
FORCEPROP 1 LAST WATTAGE 1/16W
J 2
(3850 -1300);
DISPLAY 0.404255 (3850 -1300);
FORCEPROP 1 LAST PACK_TYPE 0402LF
J 0
(3575 -1300);
DISPLAY 0.404255 (3575 -1300);
FORCEPROP 1 LAST MATERIAL CHIP
J 0
(3975 -1375);
DISPLAY 0.510638 (3975 -1375);
FORCEPROP 1 LAST LOCATION R186
J 0
(3500 -1375);
DISPLAY 0.638298 (3500 -1375);
FORCEPROP 1 LASTPIN (3600 -1375) $PN 1
J 0
(3612 -1363);
DISPLAY 0.787234 (3612 -1363);
PAINT MONO (3612 -1363);
FORCEPROP 1 LASTPIN (3800 -1375) $PN 2
J 0
(3762 -1363);
DISPLAY 0.787234 (3762 -1363);
PAINT MONO (3762 -1363);
FORCEPROP 2 LAST CDS_LIB pure_quanta
J 0
(3700 -1375);
DISPLAY INVISIBLE (3700 -1375);
FORCEPROP 1 LAST PATH I78
J 0
(3650 -1225);
DISPLAY 0.978723 (3650 -1225);
PAINT WHITE (3650 -1225);
DISPLAY INVISIBLE (3650 -1225);
FORCEPROP 0 LAST $SEC 1
J 0
(3850 -1275);
DISPLAY 0.680851 (3850 -1275);
PAINT MONO (3850 -1275);
DISPLAY INVISIBLE (3850 -1275);
FORCEPROP 0 LAST CDS_SEC 1
J 0
(3850 -1275);
DISPLAY 1.021277 (3850 -1275);
DISPLAY INVISIBLE (3850 -1275);
FORCEADD Q_RES..1
(3725 300);
FORCEPROP 1 LAST PART_NUMBER CS11002FB07
J 0
(3600 350);
DISPLAY 0.404255 (3600 350);
DISPLAY INVISIBLE (3600 350);
FORCEPROP 1 LAST PACK_TYPE 0402LF
J 0
(3600 375);
DISPLAY 0.404255 (3600 375);
FORCEPROP 1 LAST TOLERANCE 1%
J 0
(3925 300);
DISPLAY 0.510638 (3925 300);
FORCEPROP 1 LAST WATTAGE 1/16W
J 2
(3875 375);
DISPLAY 0.404255 (3875 375);
FORCEPROP 1 LAST VALUE 100
J 2
(3900 300);
DISPLAY 0.510638 (3900 300);
FORCEPROP 1 LAST MATERIAL CHIP
J 0
(4000 300);
DISPLAY 0.510638 (4000 300);
FORCEPROP 1 LAST $LOCATION R4298
J 0
(3525 300);
DISPLAY 0.638298 (3525 300);
FORCEPROP 1 LASTPIN (3625 300) $PN 1
J 0
(3637 312);
DISPLAY 0.787234 (3637 312);
PAINT MONO (3637 312);
FORCEPROP 1 LASTPIN (3825 300) $PN 2
J 0
(3787 312);
DISPLAY 0.787234 (3787 312);
PAINT MONO (3787 312);
FORCEPROP 2 LAST CDS_LIB pure_quanta
J 0
(3725 300);
DISPLAY INVISIBLE (3725 300);
FORCEPROP 1 LAST PATH I79
J 0
(3675 450);
DISPLAY 0.978723 (3675 450);
PAINT WHITE (3675 450);
DISPLAY INVISIBLE (3675 450);
FORCEPROP 0 LAST CDS_LOCATION R4298
J 0
(3875 400);
DISPLAY 1.021277 (3875 400);
DISPLAY INVISIBLE (3875 400);
FORCEPROP 0 LAST $SEC 1
J 0
(3875 400);
DISPLAY 0.680851 (3875 400);
PAINT MONO (3875 400);
DISPLAY INVISIBLE (3875 400);
FORCEPROP 0 LAST CDS_SEC 1
J 0
(3875 400);
DISPLAY 1.021277 (3875 400);
DISPLAY INVISIBLE (3875 400);
FORCEADD OFFPAGE..2
(5150 300);
FORCEPROP 2 LAST $XR0 14 
J 0
(5339 300);
DISPLAY 0.638298 (5339 300);
PAINT MONO (5339 300);
FORCEPROP 2 LAST CDS_LIB standard
J 0
(5150 300);
DISPLAY INVISIBLE (5150 300);
FORCEPROP 1 LAST OFFPAGE TRUE
J 0
(5475 175);
DISPLAY 0.872340 (5475 175);
PAINT GREEN (5475 175);
DISPLAY INVISIBLE (5475 175);
FORCEPROP 1 LAST COMMENT_BODY TRUE
J 0
(5105 205);
DISPLAY 0.872340 (5105 205);
PAINT GREEN (5105 205);
DISPLAY INVISIBLE (5105 205);
FORCEPROP 2 LAST PATH I80
J 0
(5350 350);
DISPLAY 1.021277 (5350 350);
DISPLAY INVISIBLE (5350 350);
FORCEADD Q_RES..1
(3725 1125);
FORCEPROP 1 LAST PART_NUMBER CS11002FB07
J 0
(3600 1175);
DISPLAY 0.404255 (3600 1175);
DISPLAY INVISIBLE (3600 1175);
FORCEPROP 1 LAST PACK_TYPE 0402LF
J 0
(3600 1200);
DISPLAY 0.404255 (3600 1200);
FORCEPROP 1 LAST WATTAGE 1/16W
J 2
(3875 1200);
DISPLAY 0.404255 (3875 1200);
FORCEPROP 1 LAST VALUE 100
J 2
(3900 1125);
DISPLAY 0.510638 (3900 1125);
FORCEPROP 1 LAST TOLERANCE 1%
J 0
(3925 1125);
DISPLAY 0.510638 (3925 1125);
FORCEPROP 1 LAST MATERIAL CHIP
J 0
(4000 1125);
DISPLAY 0.510638 (4000 1125);
FORCEPROP 1 LAST $LOCATION R4297
J 0
(3525 1125);
DISPLAY 0.638298 (3525 1125);
FORCEPROP 1 LASTPIN (3625 1125) $PN 1
J 0
(3637 1137);
DISPLAY 0.787234 (3637 1137);
PAINT MONO (3637 1137);
FORCEPROP 1 LASTPIN (3825 1125) $PN 2
J 0
(3787 1137);
DISPLAY 0.787234 (3787 1137);
PAINT MONO (3787 1137);
FORCEPROP 2 LAST CDS_LIB pure_quanta
J 0
(3725 1125);
DISPLAY INVISIBLE (3725 1125);
FORCEPROP 1 LAST PATH I82
J 0
(3675 1275);
DISPLAY 0.978723 (3675 1275);
PAINT WHITE (3675 1275);
DISPLAY INVISIBLE (3675 1275);
FORCEPROP 0 LAST CDS_LOCATION R4297
J 0
(3875 1225);
DISPLAY 1.021277 (3875 1225);
DISPLAY INVISIBLE (3875 1225);
FORCEPROP 0 LAST $SEC 1
J 0
(3875 1225);
DISPLAY 0.680851 (3875 1225);
PAINT MONO (3875 1225);
DISPLAY INVISIBLE (3875 1225);
FORCEPROP 0 LAST CDS_SEC 1
J 0
(3875 1225);
DISPLAY 1.021277 (3875 1225);
DISPLAY INVISIBLE (3875 1225);
FORCEADD OFFPAGE..2
(5150 1125);
FORCEPROP 2 LAST $XR0 14 
J 0
(5339 1125);
DISPLAY 0.638298 (5339 1125);
PAINT MONO (5339 1125);
FORCEPROP 2 LAST CDS_LIB standard
J 0
(5150 1125);
DISPLAY INVISIBLE (5150 1125);
FORCEPROP 1 LAST OFFPAGE TRUE
J 0
(5475 1000);
DISPLAY 0.872340 (5475 1000);
PAINT GREEN (5475 1000);
DISPLAY INVISIBLE (5475 1000);
FORCEPROP 1 LAST COMMENT_BODY TRUE
J 0
(5105 1030);
DISPLAY 0.872340 (5105 1030);
PAINT GREEN (5105 1030);
DISPLAY INVISIBLE (5105 1030);
FORCEPROP 2 LAST PATH I83
J 0
(5350 1175);
DISPLAY 1.021277 (5350 1175);
DISPLAY INVISIBLE (5350 1175);
FORCEADD Q_RES..1
(3725 1975);
FORCEPROP 1 LAST PART_NUMBER CS11002FB07
J 0
(3600 2025);
DISPLAY 0.404255 (3600 2025);
DISPLAY INVISIBLE (3600 2025);
FORCEPROP 1 LAST PACK_TYPE 0402LF
J 0
(3600 2050);
DISPLAY 0.404255 (3600 2050);
FORCEPROP 1 LAST MATERIAL CHIP
J 0
(4000 1975);
DISPLAY 0.510638 (4000 1975);
FORCEPROP 1 LAST TOLERANCE 1%
J 0
(3925 1975);
DISPLAY 0.510638 (3925 1975);
FORCEPROP 1 LAST VALUE 100
J 2
(3900 1975);
DISPLAY 0.510638 (3900 1975);
FORCEPROP 1 LAST WATTAGE 1/16W
J 2
(3875 2050);
DISPLAY 0.404255 (3875 2050);
FORCEPROP 1 LAST $LOCATION R4296
J 0
(3525 1975);
DISPLAY 0.638298 (3525 1975);
FORCEPROP 1 LASTPIN (3625 1975) $PN 1
J 0
(3637 1987);
DISPLAY 0.787234 (3637 1987);
PAINT MONO (3637 1987);
FORCEPROP 1 LASTPIN (3825 1975) $PN 2
J 0
(3787 1987);
DISPLAY 0.787234 (3787 1987);
PAINT MONO (3787 1987);
FORCEPROP 2 LAST CDS_LIB pure_quanta
J 0
(3725 1975);
DISPLAY INVISIBLE (3725 1975);
FORCEPROP 1 LAST PATH I85
J 0
(3675 2125);
DISPLAY 0.978723 (3675 2125);
PAINT WHITE (3675 2125);
DISPLAY INVISIBLE (3675 2125);
FORCEPROP 0 LAST CDS_LOCATION R4296
J 0
(3875 2075);
DISPLAY 1.021277 (3875 2075);
DISPLAY INVISIBLE (3875 2075);
FORCEPROP 0 LAST $SEC 1
J 0
(3875 2075);
DISPLAY 0.680851 (3875 2075);
PAINT MONO (3875 2075);
DISPLAY INVISIBLE (3875 2075);
FORCEPROP 0 LAST CDS_SEC 1
J 0
(3875 2075);
DISPLAY 1.021277 (3875 2075);
DISPLAY INVISIBLE (3875 2075);
FORCEADD OFFPAGE..2
(5150 1975);
FORCEPROP 2 LAST $XR0 14 
J 0
(5339 1975);
DISPLAY 0.638298 (5339 1975);
PAINT MONO (5339 1975);
FORCEPROP 2 LAST CDS_LIB standard
J 0
(5150 1975);
DISPLAY INVISIBLE (5150 1975);
FORCEPROP 1 LAST OFFPAGE TRUE
J 0
(5475 1850);
DISPLAY 0.872340 (5475 1850);
PAINT GREEN (5475 1850);
DISPLAY INVISIBLE (5475 1850);
FORCEPROP 1 LAST COMMENT_BODY TRUE
J 0
(5105 1880);
DISPLAY 0.872340 (5105 1880);
PAINT GREEN (5105 1880);
DISPLAY INVISIBLE (5105 1880);
FORCEPROP 2 LAST PATH I86
J 0
(5350 2025);
DISPLAY 1.021277 (5350 2025);
DISPLAY INVISIBLE (5350 2025);
FORCEADD Q_RES..1
(3725 2800);
FORCEPROP 1 LAST PART_NUMBER CS11002FB07
J 0
(3600 2850);
DISPLAY 0.404255 (3600 2850);
DISPLAY INVISIBLE (3600 2850);
FORCEPROP 1 LAST PACK_TYPE 0402LF
J 0
(3600 2875);
DISPLAY 0.404255 (3600 2875);
FORCEPROP 1 LAST MATERIAL CHIP
J 0
(4000 2800);
DISPLAY 0.510638 (4000 2800);
FORCEPROP 1 LAST TOLERANCE 1%
J 0
(3925 2800);
DISPLAY 0.510638 (3925 2800);
FORCEPROP 1 LAST VALUE 100
J 2
(3900 2800);
DISPLAY 0.510638 (3900 2800);
FORCEPROP 1 LAST WATTAGE 1/16W
J 2
(3875 2875);
DISPLAY 0.404255 (3875 2875);
FORCEPROP 1 LAST $LOCATION R4295
J 0
(3525 2800);
DISPLAY 0.638298 (3525 2800);
FORCEPROP 1 LASTPIN (3625 2800) $PN 1
J 0
(3637 2812);
DISPLAY 0.787234 (3637 2812);
PAINT MONO (3637 2812);
FORCEPROP 1 LASTPIN (3825 2800) $PN 2
J 0
(3787 2812);
DISPLAY 0.787234 (3787 2812);
PAINT MONO (3787 2812);
FORCEPROP 2 LAST CDS_LIB pure_quanta
J 0
(3725 2800);
DISPLAY INVISIBLE (3725 2800);
FORCEPROP 1 LAST PATH I87
J 0
(3675 2950);
DISPLAY 0.978723 (3675 2950);
PAINT WHITE (3675 2950);
DISPLAY INVISIBLE (3675 2950);
FORCEPROP 0 LAST CDS_LOCATION R4295
J 0
(3875 2900);
DISPLAY 1.021277 (3875 2900);
DISPLAY INVISIBLE (3875 2900);
FORCEPROP 0 LAST $SEC 1
J 0
(3875 2900);
DISPLAY 0.680851 (3875 2900);
PAINT MONO (3875 2900);
DISPLAY INVISIBLE (3875 2900);
FORCEPROP 0 LAST CDS_SEC 1
J 0
(3875 2900);
DISPLAY 1.021277 (3875 2900);
DISPLAY INVISIBLE (3875 2900);
FORCEADD OFFPAGE..2
(5150 2800);
FORCEPROP 2 LAST $XR0 14 
J 0
(5339 2800);
DISPLAY 0.638298 (5339 2800);
PAINT MONO (5339 2800);
FORCEPROP 2 LAST CDS_LIB standard
J 0
(5150 2800);
DISPLAY INVISIBLE (5150 2800);
FORCEPROP 1 LAST OFFPAGE TRUE
J 0
(5475 2675);
DISPLAY 0.872340 (5475 2675);
PAINT GREEN (5475 2675);
DISPLAY INVISIBLE (5475 2675);
FORCEPROP 1 LAST COMMENT_BODY TRUE
J 0
(5105 2705);
DISPLAY 0.872340 (5105 2705);
PAINT GREEN (5105 2705);
DISPLAY INVISIBLE (5105 2705);
FORCEPROP 2 LAST PATH I88
J 0
(5350 2850);
DISPLAY 1.021277 (5350 2850);
DISPLAY INVISIBLE (5350 2850);
FORCEADD QUANTA_TITLE_BLOCK_C..1
(6275 -2775);
FORCEPROP 0 LAST CDS_CON_LAST_MODIFIED Fri Aug 25 14:01:44 2023
J 0
(4390 -2760);
PAINT MONO (4390 -2760);
DISPLAY INVISIBLE (4390 -2760);
FORCEPROP 2 LAST CUSTOM_TXT_CDS <XR_PAGE_TITLE>
J 0
(-1615 2475);
DISPLAY 0.638298 (-1615 2475);
PAINT PINK (-1615 2475);
DISPLAY INVISIBLE (-1615 2475);
FORCEPROP 2 LAST CUSTOM_TXT_CDS <Q_NUMBER>
J 0
(4872 -2672);
DISPLAY 1.212766 (4872 -2672);
FORCEPROP 2 LAST CUSTOM_TXT_CDS <CON_LAST_MODIFIED>
J 0
(4390 -2760);
DISPLAY 0.978723 (4390 -2760);
FORCEPROP 2 LAST CUSTOM_TXT_CDS <Q_PROJ>
J 0
(3893 -2673);
DISPLAY 1.212766 (3893 -2673);
FORCEPROP 2 LAST CUSTOM_TXT_CDS <CON_PAGE_NUM> OF <CON_TOTAL_PAGES>
J 0
(5829 -2757);
DISPLAY 0.978723 (5829 -2757);
FORCEPROP 2 LAST CUSTOM_TXT_CDS <Q_REV>
J 0
(6091 -2672);
DISPLAY 1.212766 (6091 -2672);
FORCEPROP 2 LAST CUSTOM_TXT_CDS <NAME_1>
J 0
(3100 -2600);
FORCEPROP 2 LAST CUSTOM_TXT_CDS <NAME_2>
J 0
(3100 -2725);
FORCEPROP 1 LAST Q_TITLE SPR CPU0 & 1 - CPU0 PWRGDS/RESET
J 0
(-2991 -2774);
DISPLAY 2.446809 (-2991 -2774);
PAINT GREEN (-2991 -2774);
FORCEPROP 1 LAST Q_DEPT 
J 1
(2512 -2726);
DISPLAY 1.957447 (2512 -2726);
PAINT GREEN (2512 -2726);
FORCEPROP 2 LAST CDS_XR_PAGE_TITLE CR-124 : @S9S_MB_2U_LIB.S9S_MB_2U(SCH_1):PAGE124
J 0
(-1615 2475);
DISPLAY 0.638298 (-1615 2475);
PAINT PINK (-1615 2475);
DISPLAY INVISIBLE (-1615 2475);
FORCEPROP 1 LAST COMMENT_BODY TRUE
J 0
(6287 -2788);
DISPLAY 0.978723 (6287 -2788);
PAINT GREEN (6287 -2788);
DISPLAY INVISIBLE (6287 -2788);
FORCEPROP 2 LAST PAGE_BORDER TRUE
J 0
(-1615 2475);
DISPLAY 0.638298 (-1615 2475);
PAINT PINK (-1615 2475);
DISPLAY INVISIBLE (-1615 2475);
FORCEPROP 1 LAST CDS_LMAN_SYM_OUTLINE -9475,6775,100,-125
J 0
(6275 -2775);
DISPLAY 0.468085 (6275 -2775);
PAINT GREEN (6275 -2775);
DISPLAY INVISIBLE (6275 -2775);
FORCEPROP 2 LAST CDS_LIB pure_quanta
J 0
(6275 -2775);
PAINT MONO (6275 -2775);
DISPLAY INVISIBLE (6275 -2775);
WIRE 16 -1 (4325 525)(4325 475);
WIRE 16 -1 (4325 1350)(4325 1300);
WIRE 16 -1 (4300 -300)(4300 -350);
WIRE 16 -1 (4325 2200)(4325 2150);
WIRE 16 -1 (4325 3025)(4325 2975);
WIRE 16 -1 (4300 -1150)(4300 -1200);
WIRE 16 -1 (3825 475)(4325 475);
WIRE 16 2175 (3525 400)(4100 400);
WIRE 16 2175 (4100 400)(4100 250);
WIRE 16 2175 (3525 400)(3525 250);
WIRE 16 2175 (3525 250)(4100 250);
WIRE 16 -1 (3825 300)(5100 300);
FORCEPROP 2 LAST SIG_NAME PWRGD_DRAMPWRGD_CPU0_GH_LVC1_R
J 0
(4240 310);
DISPLAY 0.553191 (4240 310);
PAINT WHITE (4240 310);
WIRE 16 2175 (3525 1225)(4100 1225);
WIRE 16 2175 (4100 1225)(4100 1075);
WIRE 16 2175 (3525 1225)(3525 1075);
WIRE 16 2175 (3525 1075)(4100 1075);
WIRE 16 -1 (3825 1300)(4325 1300);
WIRE 16 2175 (3525 2100)(4100 2100);
WIRE 16 2175 (4100 2100)(4100 1950);
WIRE 16 2175 (3525 2100)(3525 1950);
WIRE 16 2175 (3525 1950)(4100 1950);
WIRE 16 -1 (3825 1975)(5100 1975);
FORCEPROP 2 LAST SIG_NAME PWRGD_DRAMPWRGD_CPU0_CD_LVC1_R
J 0
(4290 1985);
DISPLAY 0.553191 (4290 1985);
PAINT WHITE (4290 1985);
WIRE 16 -1 (3825 2150)(4325 2150);
WIRE 16 -1 (3825 1125)(5100 1125);
FORCEPROP 2 LAST SIG_NAME PWRGD_DRAMPWRGD_CPU0_EF_LVC1_R
J 0
(4290 1135);
DISPLAY 0.553191 (4290 1135);
PAINT WHITE (4290 1135);
WIRE 16 -1 (3375 2975)(3625 2975);
WIRE 16 -1 (3375 2975)(3375 2800);
WIRE 16 -1 (3375 2800)(3625 2800);
WIRE 16 -1 (-450 2800)(3375 2800);
FORCEPROP 2 LAST SIG_NAME PWRGD_DRAMPWRGD_CPU0_AB_LVC1_R2
J 0
(2540 2810);
DISPLAY 0.553191 (2540 2810);
PAINT WHITE (2540 2810);
WIRE 16 2175 (3500 -400)(4075 -400);
WIRE 16 2175 (4075 -400)(4075 -550);
WIRE 16 2175 (3500 -400)(3500 -550);
WIRE 16 2175 (3500 -550)(4075 -550);
WIRE 16 2175 (3525 2775)(4100 2775);
WIRE 16 2175 (4100 2925)(4100 2775);
WIRE 16 2175 (3525 2925)(3525 2775);
WIRE 16 2175 (3525 2925)(4100 2925);
WIRE 16 -1 (3800 -350)(4300 -350);
WIRE 16 -1 (-450 300)(3375 300);
FORCEPROP 2 LAST SIG_NAME PWRGD_DRAMPWRGD_CPU0_GH_LVC1_R2
J 0
(2540 310);
DISPLAY 0.553191 (2540 310);
PAINT WHITE (2540 310);
WIRE 16 -1 (3375 300)(3625 300);
WIRE 16 -1 (3375 300)(3375 475);
WIRE 16 -1 (3375 475)(3625 475);
WIRE 16 -1 (3825 2800)(5100 2800);
FORCEPROP 2 LAST SIG_NAME PWRGD_DRAMPWRGD_CPU0_AB_LVC1_R
J 0
(4240 2810);
DISPLAY 0.553191 (4240 2810);
PAINT WHITE (4240 2810);
WIRE 16 -1 (3375 2150)(3625 2150);
WIRE 16 -1 (3375 1975)(3625 1975);
WIRE 16 -1 (3375 2150)(3375 1975);
FORCEPROP 2 LAST SIG_NAME PWRGD_DRAMPWRGD_CPU0_CD_LVC1_R2
J 0
(2565 1985);
DISPLAY 0.553191 (2565 1985);
PAINT WHITE (2565 1985);
WIRE 16 -1 (-450 1975)(3375 1975);
WIRE 16 -1 (3375 1300)(3625 1300);
WIRE 16 -1 (3375 1125)(3375 1300);
WIRE 16 -1 (3375 1125)(3625 1125);
WIRE 16 -1 (-450 1125)(3375 1125);
FORCEPROP 2 LAST SIG_NAME PWRGD_DRAMPWRGD_CPU0_EF_LVC1_R2
J 0
(2540 1135);
DISPLAY 0.553191 (2540 1135);
PAINT WHITE (2540 1135);
WIRE 16 -1 (-450 -525)(3375 -525);
FORCEPROP 2 LAST SIG_NAME PWRGD_CPU0_BUF_R
J 0
(2740 -515);
DISPLAY 0.553191 (2740 -515);
PAINT WHITE (2740 -515);
WIRE 16 -1 (3600 -525)(3375 -525);
WIRE 16 -1 (3375 -350)(3375 -525);
WIRE 16 -1 (3375 -350)(3600 -350);
WIRE 16 -1 (3375 -1200)(3600 -1200);
WIRE 16 -1 (3375 -1200)(3375 -1375);
WIRE 16 -1 (3600 -1375)(3375 -1375);
WIRE 16 -1 (-450 -1375)(3375 -1375);
FORCEPROP 2 LAST SIG_NAME RST_CPU0_BUF_R_N
J 0
(2740 -1365);
DISPLAY 0.553191 (2740 -1365);
PAINT WHITE (2740 -1365);
WIRE 16 2175 (3500 -1425)(4075 -1425);
WIRE 16 2175 (4075 -1275)(4075 -1425);
WIRE 16 2175 (3500 -1275)(3500 -1425);
WIRE 16 2175 (3500 -1275)(4075 -1275);
WIRE 16 -1 (4650 -1375)(3800 -1375);
FORCEPROP 2 LAST SIG_NAME RST_CPU0_LVC1_N
J 0
(4115 -1365);
DISPLAY 0.553191 (4115 -1365);
PAINT WHITE (4115 -1365);
WIRE 16 -1 (4650 -525)(3800 -525);
FORCEPROP 2 LAST SIG_NAME PWRGD_CPU0_LVC1
J 0
(4140 -515);
DISPLAY 0.553191 (4140 -515);
PAINT WHITE (4140 -515);
WIRE 16 -1 (3825 2975)(4325 2975);
WIRE 16 -1 (-1875 2800)(-650 2800);
FORCEPROP 2 LAST SIG_NAME PWRGD_DRAMPWRGD_CPU0_AB_R_LVC1
J 0
(-1760 2810);
DISPLAY 0.553191 (-1760 2810);
PAINT WHITE (-1760 2810);
WIRE 16 -1 (-1875 1125)(-650 1125);
FORCEPROP 2 LAST SIG_NAME PWRGD_DRAMPWRGD_CPU0_EF_R_LVC1
J 0
(-1760 1135);
DISPLAY 0.553191 (-1760 1135);
PAINT WHITE (-1760 1135);
WIRE 16 -1 (-650 -1375)(-1875 -1375);
FORCEPROP 2 LAST SIG_NAME RST_CPU0_LVC1_R_N
J 0
(-1760 -1365);
DISPLAY 0.553191 (-1760 -1365);
PAINT WHITE (-1760 -1365);
WIRE 16 -1 (-1875 -525)(-650 -525);
FORCEPROP 2 LAST SIG_NAME PWRGD_CPU0_LVC1_R
J 0
(-1760 -515);
DISPLAY 0.553191 (-1760 -515);
PAINT WHITE (-1760 -515);
WIRE 16 -1 (-1875 1975)(-650 1975);
FORCEPROP 2 LAST SIG_NAME PWRGD_DRAMPWRGD_CPU0_CD_R_LVC1
J 0
(-1760 1985);
DISPLAY 0.553191 (-1760 1985);
PAINT WHITE (-1760 1985);
WIRE 16 -1 (3800 -1200)(4300 -1200);
WIRE 16 -1 (-1875 300)(-650 300);
FORCEPROP 2 LAST SIG_NAME PWRGD_DRAMPWRGD_CPU0_GH_R_LVC1
J 0
(-1760 310);
DISPLAY 0.553191 (-1760 310);
PAINT WHITE (-1760 310);
DOT 1 (3375 2800);
DOT 1 (3375 1975);
DOT 1 (3375 1125);
DOT 1 (3375 300);
DOT 1 (3375 -525);
DOT 1 (3375 -1375);
FORCENOTE
20211206 ADD R4295,R4296,R4297,R4298
(3150 175) 0;
DISPLAY LEFT (3150 175);
DISPLAY 1.063830 (3150 175);
PAINT WHITE (3150 175);
FORCENOTE
20211129 R184 CHANGE TO 100 OHM
(3125 -675) 0;
DISPLAY LEFT (3125 -675);
DISPLAY 1.063830 (3125 -675);
PAINT WHITE (3125 -675);
FORCENOTE
20211129 R186 CHANGE TO 100 OHM
(3125 -1550) 0;
DISPLAY LEFT (3125 -1550);
DISPLAY 1.063830 (3125 -1550);
PAINT WHITE (3125 -1550);
FORCENOTE
CPLD
(-2075 2900) 0;
DISPLAY LEFT (-2075 2900);
DISPLAY 1.276596 (-2075 2900);
PAINT SKYBLUE (-2075 2900);
FORCENOTE
20210907 MODIFY FOR GT
(-2400 3425) 0;
DISPLAY LEFT (-2400 3425);
DISPLAY 2.510638 (-2400 3425);
PAINT PINK (-2400 3425);
FORCENOTE
CPLD
(-2075 2075) 0;
DISPLAY LEFT (-2075 2075);
DISPLAY 1.276596 (-2075 2075);
PAINT SKYBLUE (-2075 2075);
FORCENOTE
CPLD
(-2075 -1275) 0;
DISPLAY LEFT (-2075 -1275);
DISPLAY 1.276596 (-2075 -1275);
PAINT SKYBLUE (-2075 -1275);
FORCENOTE
CPLD
(-2075 -425) 0;
DISPLAY LEFT (-2075 -425);
DISPLAY 1.276596 (-2075 -425);
PAINT SKYBLUE (-2075 -425);
FORCENOTE
CPLD
(-2075 400) 0;
DISPLAY LEFT (-2075 400);
DISPLAY 1.276596 (-2075 400);
PAINT SKYBLUE (-2075 400);
FORCENOTE
CPLD
(-2075 1225) 0;
DISPLAY LEFT (-2075 1225);
DISPLAY 1.276596 (-2075 1225);
PAINT SKYBLUE (-2075 1225);
QUIT
